(kicad_pcb
	(version 20260206)
	(generator "pcbnew")
	(generator_version "10.0")
	(general
		(thickness 1.6)
		(legacy_teardrops no)
	)
	(paper "A4")
	(title_block
		(title "01162023_DA0F0TEBIF0_F0T_Expander_BD_F_brd_V02_OCP.brd")
		(comment 1 "Grand Teton / footprints 6639-6645 of 9728")
	)
	(layers
		(0 "F.Cu" signal "TOP")
		(4 "In1.Cu" signal "GND")
		(6 "In2.Cu" signal "VCC")
		(8 "In3.Cu" signal "VCC1")
		(10 "In4.Cu" signal "GND1")
		(12 "In5.Cu" signal "IN1")
		(14 "In6.Cu" signal "GND2")
		(16 "In7.Cu" signal "IN2")
		(18 "In8.Cu" signal "GND3")
		(20 "In9.Cu" signal "IN3")
		(22 "In10.Cu" signal "GND4")
		(24 "In11.Cu" signal "IN4")
		(26 "In12.Cu" signal "GND5")
		(28 "In13.Cu" signal "IN5")
		(30 "In14.Cu" signal "GND6")
		(32 "In15.Cu" signal "IN6")
		(34 "In16.Cu" signal "GND7")
		(2 "B.Cu" signal "BOTTOM")
		(9 "F.Adhes" user "F.Adhesive")
		(11 "B.Adhes" user "B.Adhesive")
		(13 "F.Paste" user "Package Geometry/Pastemask Top")
		(15 "B.Paste" user "Package Geometry/Pastemask Bottom")
		(5 "F.SilkS" user "Ref Des/Silkscreen Top")
		(7 "B.SilkS" user "Ref Des/Silkscreen Bottom")
		(1 "F.Mask" user "Board Geometry/Soldermask Top")
		(3 "B.Mask" user "Board Geometry/Soldermask Bottom")
		(17 "Dwgs.User" user "User.Drawings")
		(19 "Cmts.User" user "User.Comments")
		(21 "Eco1.User" user "User.Eco1")
		(23 "Eco2.User" user "User.Eco2")
		(25 "Edge.Cuts" user "Board Geometry/Outline")
		(27 "Margin" user)
		(31 "F.CrtYd" user "Package Geometry/Place Bound Top")
		(29 "B.CrtYd" user "Package Geometry/Place Bound Bottom")
		(35 "F.Fab" user "Ref Des/Assembly Top")
		(33 "B.Fab" user "Ref Des/Assembly Bottom")
	)
	(footprint ""
		(layer "F.Cu")
		(at 220.493844 -96.139 90)
		(property "Reference" "R720"
			(at 0 0 90)
			(layer "F.SilkS")
			(hide yes)
			(effects
				(font
					(size 1.27 1.27)
				)
			)
		)
		(property "Value" ""
			(at 0 0 90)
			(layer "F.Fab")
			(effects
				(font
					(size 1.27 1.27)
				)
			)
		)
		(duplicate_pad_numbers_are_jumpers no)
		(fp_line
			(start 0.7874 -0.4064)
			(end 0.7874 0.4064)
			(stroke
				(width 0.1524)
				(type default)
			)
			(layer "F.SilkS")
		)
		(fp_line
			(start -0.7874 -0.4064)
			(end 0.7874 -0.4064)
			(stroke
				(width 0.1524)
				(type default)
			)
			(layer "F.SilkS")
		)
		(fp_line
			(start 0.7874 0.4064)
			(end -0.7874 0.4064)
			(stroke
				(width 0.1524)
				(type default)
			)
			(layer "F.SilkS")
		)
		(fp_line
			(start -0.7874 0.4064)
			(end -0.7874 -0.4064)
			(stroke
				(width 0.1524)
				(type default)
			)
			(layer "F.SilkS")
		)
		(fp_line
			(start -0.12065 -0.305054)
			(end -0.12065 -0.2794)
			(stroke
				(width 0.1)
				(type default)
			)
			(layer "F.Fab")
		)
		(fp_line
			(start -0.67945 -0.305054)
			(end -0.12065 -0.305054)
			(stroke
				(width 0.1)
				(type default)
			)
			(layer "F.Fab")
		)
		(fp_line
			(start 0.67945 -0.3048)
			(end 0.67945 0.3048)
			(stroke
				(width 0.1)
				(type default)
			)
			(layer "F.Fab")
		)
		(fp_line
			(start 0.12065 -0.3048)
			(end 0.67945 -0.3048)
			(stroke
				(width 0.1)
				(type default)
			)
			(layer "F.Fab")
		)
		(fp_line
			(start 0.12065 -0.2794)
			(end 0.12065 -0.3048)
			(stroke
				(width 0.1)
				(type default)
			)
			(layer "F.Fab")
		)
		(fp_line
			(start -0.12065 -0.2794)
			(end 0.12065 -0.2794)
			(stroke
				(width 0.1)
				(type default)
			)
			(layer "F.Fab")
		)
		(fp_line
			(start 0.120396 0.2794)
			(end -0.12065 0.2794)
			(stroke
				(width 0.1)
				(type default)
			)
			(layer "F.Fab")
		)
		(fp_line
			(start -0.12065 0.2794)
			(end -0.12065 0.3048)
			(stroke
				(width 0.1)
				(type default)
			)
			(layer "F.Fab")
		)
		(fp_line
			(start 0.67945 0.3048)
			(end 0.120396 0.3048)
			(stroke
				(width 0.1)
				(type default)
			)
			(layer "F.Fab")
		)
		(fp_line
			(start 0.120396 0.3048)
			(end 0.120396 0.2794)
			(stroke
				(width 0.1)
				(type default)
			)
			(layer "F.Fab")
		)
		(fp_line
			(start -0.12065 0.3048)
			(end -0.67945 0.3048)
			(stroke
				(width 0.1)
				(type default)
			)
			(layer "F.Fab")
		)
		(fp_line
			(start -0.67945 0.3048)
			(end -0.67945 -0.305054)
			(stroke
				(width 0.1)
				(type default)
			)
			(layer "F.Fab")
		)
		(pad "1" smd circle
			(at -0.40005 0 90)
			(size 0 0)
			(layers "F.Cu" "F.Mask" "F.Paste")
			(net "SMB_BIC_I2C6_MUX_NIC_ADC_R_SCL")
		)
		(pad "2" smd circle
			(at 0.40005 0 90)
			(size 0 0)
			(layers "F.Cu" "F.Mask" "F.Paste")
			(net "SMB_NIC3_ADC_SCL")
		)
	)
	(footprint ""
		(layer "F.Cu")
		(at 191.767968 -19.453098)
		(property "Reference" "R1681"
			(at 0 0 0)
			(layer "F.SilkS")
			(hide yes)
			(effects
				(font
					(size 1.27 1.27)
				)
			)
		)
		(property "Value" ""
			(at 0 0 0)
			(layer "F.Fab")
			(effects
				(font
					(size 1.27 1.27)
				)
			)
		)
		(duplicate_pad_numbers_are_jumpers no)
		(fp_line
			(start -0.7874 -0.4064)
			(end 0.7874 -0.4064)
			(stroke
				(width 0.1524)
				(type default)
			)
			(layer "F.SilkS")
		)
		(fp_line
			(start -0.7874 0.4064)
			(end -0.7874 -0.4064)
			(stroke
				(width 0.1524)
				(type default)
			)
			(layer "F.SilkS")
		)
		(fp_line
			(start 0.7874 -0.4064)
			(end 0.7874 0.4064)
			(stroke
				(width 0.1524)
				(type default)
			)
			(layer "F.SilkS")
		)
		(fp_line
			(start 0.7874 0.4064)
			(end -0.7874 0.4064)
			(stroke
				(width 0.1524)
				(type default)
			)
			(layer "F.SilkS")
		)
		(fp_line
			(start -0.67945 -0.305054)
			(end -0.12065 -0.305054)
			(stroke
				(width 0.1)
				(type default)
			)
			(layer "F.Fab")
		)
		(fp_line
			(start -0.67945 0.3048)
			(end -0.67945 -0.305054)
			(stroke
				(width 0.1)
				(type default)
			)
			(layer "F.Fab")
		)
		(fp_line
			(start -0.12065 -0.305054)
			(end -0.12065 -0.2794)
			(stroke
				(width 0.1)
				(type default)
			)
			(layer "F.Fab")
		)
		(fp_line
			(start -0.12065 -0.2794)
			(end 0.12065 -0.2794)
			(stroke
				(width 0.1)
				(type default)
			)
			(layer "F.Fab")
		)
		(fp_line
			(start -0.12065 0.2794)
			(end -0.12065 0.3048)
			(stroke
				(width 0.1)
				(type default)
			)
			(layer "F.Fab")
		)
		(fp_line
			(start -0.12065 0.3048)
			(end -0.67945 0.3048)
			(stroke
				(width 0.1)
				(type default)
			)
			(layer "F.Fab")
		)
		(fp_line
			(start 0.120396 0.2794)
			(end -0.12065 0.2794)
			(stroke
				(width 0.1)
				(type default)
			)
			(layer "F.Fab")
		)
		(fp_line
			(start 0.120396 0.3048)
			(end 0.120396 0.2794)
			(stroke
				(width 0.1)
				(type default)
			)
			(layer "F.Fab")
		)
		(fp_line
			(start 0.12065 -0.3048)
			(end 0.67945 -0.3048)
			(stroke
				(width 0.1)
				(type default)
			)
			(layer "F.Fab")
		)
		(fp_line
			(start 0.12065 -0.2794)
			(end 0.12065 -0.3048)
			(stroke
				(width 0.1)
				(type default)
			)
			(layer "F.Fab")
		)
		(fp_line
			(start 0.67945 -0.3048)
			(end 0.67945 0.3048)
			(stroke
				(width 0.1)
				(type default)
			)
			(layer "F.Fab")
		)
		(fp_line
			(start 0.67945 0.3048)
			(end 0.120396 0.3048)
			(stroke
				(width 0.1)
				(type default)
			)
			(layer "F.Fab")
		)
		(pad "1" smd circle
			(at -0.40005 0)
			(size 0 0)
			(layers "F.Cu" "F.Mask" "F.Paste")
			(net "SMB_ISO_SSD6_R_SDA")
		)
		(pad "2" smd circle
			(at 0.40005 0)
			(size 0 0)
			(layers "F.Cu" "F.Mask" "F.Paste")
			(net "SMB_ISO_SSD6_SDA")
		)
	)
	(footprint ""
		(layer "F.Cu")
		(at 366.226598 -25.432004 -90)
		(property "Reference" "C977"
			(at 0 0 270)
			(layer "F.SilkS")
			(hide yes)
			(effects
				(font
					(size 1.27 1.27)
				)
			)
		)
		(property "Value" ""
			(at 0 0 270)
			(layer "F.Fab")
			(effects
				(font
					(size 1.27 1.27)
				)
			)
		)
		(duplicate_pad_numbers_are_jumpers no)
		(fp_line
			(start -0.7874 0.4064)
			(end -0.7874 -0.4064)
			(stroke
				(width 0.1524)
				(type default)
			)
			(layer "F.SilkS")
		)
		(fp_line
			(start 0.7874 0.4064)
			(end -0.7874 0.4064)
			(stroke
				(width 0.1524)
				(type default)
			)
			(layer "F.SilkS")
		)
		(fp_line
			(start -0.7874 -0.4064)
			(end 0.7874 -0.4064)
			(stroke
				(width 0.1524)
				(type default)
			)
			(layer "F.SilkS")
		)
		(fp_line
			(start 0.7874 -0.4064)
			(end 0.7874 0.4064)
			(stroke
				(width 0.1524)
				(type default)
			)
			(layer "F.SilkS")
		)
		(fp_line
			(start -0.67945 0.3048)
			(end -0.67945 -0.305054)
			(stroke
				(width 0.1)
				(type default)
			)
			(layer "F.Fab")
		)
		(fp_line
			(start -0.12065 0.3048)
			(end -0.67945 0.3048)
			(stroke
				(width 0.1)
				(type default)
			)
			(layer "F.Fab")
		)
		(fp_line
			(start 0.120396 0.3048)
			(end 0.120396 0.2794)
			(stroke
				(width 0.1)
				(type default)
			)
			(layer "F.Fab")
		)
		(fp_line
			(start 0.67945 0.3048)
			(end 0.120396 0.3048)
			(stroke
				(width 0.1)
				(type default)
			)
			(layer "F.Fab")
		)
		(fp_line
			(start -0.12065 0.2794)
			(end -0.12065 0.3048)
			(stroke
				(width 0.1)
				(type default)
			)
			(layer "F.Fab")
		)
		(fp_line
			(start 0.120396 0.2794)
			(end -0.12065 0.2794)
			(stroke
				(width 0.1)
				(type default)
			)
			(layer "F.Fab")
		)
		(fp_line
			(start -0.12065 -0.2794)
			(end 0.12065 -0.2794)
			(stroke
				(width 0.1)
				(type default)
			)
			(layer "F.Fab")
		)
		(fp_line
			(start 0.12065 -0.2794)
			(end 0.12065 -0.3048)
			(stroke
				(width 0.1)
				(type default)
			)
			(layer "F.Fab")
		)
		(fp_line
			(start 0.12065 -0.3048)
			(end 0.67945 -0.3048)
			(stroke
				(width 0.1)
				(type default)
			)
			(layer "F.Fab")
		)
		(fp_line
			(start 0.67945 -0.3048)
			(end 0.67945 0.3048)
			(stroke
				(width 0.1)
				(type default)
			)
			(layer "F.Fab")
		)
		(fp_line
			(start -0.67945 -0.305054)
			(end -0.12065 -0.305054)
			(stroke
				(width 0.1)
				(type default)
			)
			(layer "F.Fab")
		)
		(fp_line
			(start -0.12065 -0.305054)
			(end -0.12065 -0.2794)
			(stroke
				(width 0.1)
				(type default)
			)
			(layer "F.Fab")
		)
		(pad "1" smd circle
			(at -0.40005 0 270)
			(size 0 0)
			(layers "F.Cu" "F.Mask" "F.Paste")
			(net "GND")
		)
		(pad "2" smd circle
			(at 0.40005 0 270)
			(size 0 0)
			(layers "F.Cu" "F.Mask" "F.Paste")
			(net "P3V3_SSD12")
		)
	)
	(footprint ""
		(layer "F.Cu")
		(at 329.671426 -25.342342 -90)
		(property "Reference" "R442"
			(at 0 0 270)
			(layer "F.SilkS")
			(hide yes)
			(effects
				(font
					(size 1.27 1.27)
				)
			)
		)
		(property "Value" ""
			(at 0 0 270)
			(layer "F.Fab")
			(effects
				(font
					(size 1.27 1.27)
				)
			)
		)
		(duplicate_pad_numbers_are_jumpers no)
		(fp_line
			(start -0.7874 0.4064)
			(end -0.7874 -0.4064)
			(stroke
				(width 0.1524)
				(type default)
			)
			(layer "F.SilkS")
		)
		(fp_line
			(start 0.7874 0.4064)
			(end -0.7874 0.4064)
			(stroke
				(width 0.1524)
				(type default)
			)
			(layer "F.SilkS")
		)
		(fp_line
			(start -0.7874 -0.4064)
			(end 0.7874 -0.4064)
			(stroke
				(width 0.1524)
				(type default)
			)
			(layer "F.SilkS")
		)
		(fp_line
			(start 0.7874 -0.4064)
			(end 0.7874 0.4064)
			(stroke
				(width 0.1524)
				(type default)
			)
			(layer "F.SilkS")
		)
		(fp_line
			(start -0.67945 0.3048)
			(end -0.67945 -0.305054)
			(stroke
				(width 0.1)
				(type default)
			)
			(layer "F.Fab")
		)
		(fp_line
			(start -0.12065 0.3048)
			(end -0.67945 0.3048)
			(stroke
				(width 0.1)
				(type default)
			)
			(layer "F.Fab")
		)
		(fp_line
			(start 0.120396 0.3048)
			(end 0.120396 0.2794)
			(stroke
				(width 0.1)
				(type default)
			)
			(layer "F.Fab")
		)
		(fp_line
			(start 0.67945 0.3048)
			(end 0.120396 0.3048)
			(stroke
				(width 0.1)
				(type default)
			)
			(layer "F.Fab")
		)
		(fp_line
			(start -0.12065 0.2794)
			(end -0.12065 0.3048)
			(stroke
				(width 0.1)
				(type default)
			)
			(layer "F.Fab")
		)
		(fp_line
			(start 0.120396 0.2794)
			(end -0.12065 0.2794)
			(stroke
				(width 0.1)
				(type default)
			)
			(layer "F.Fab")
		)
		(fp_line
			(start -0.12065 -0.2794)
			(end 0.12065 -0.2794)
			(stroke
				(width 0.1)
				(type default)
			)
			(layer "F.Fab")
		)
		(fp_line
			(start 0.12065 -0.2794)
			(end 0.12065 -0.3048)
			(stroke
				(width 0.1)
				(type default)
			)
			(layer "F.Fab")
		)
		(fp_line
			(start 0.12065 -0.3048)
			(end 0.67945 -0.3048)
			(stroke
				(width 0.1)
				(type default)
			)
			(layer "F.Fab")
		)
		(fp_line
			(start 0.67945 -0.3048)
			(end 0.67945 0.3048)
			(stroke
				(width 0.1)
				(type default)
			)
			(layer "F.Fab")
		)
		(fp_line
			(start -0.67945 -0.305054)
			(end -0.12065 -0.305054)
			(stroke
				(width 0.1)
				(type default)
			)
			(layer "F.Fab")
		)
		(fp_line
			(start -0.12065 -0.305054)
			(end -0.12065 -0.2794)
			(stroke
				(width 0.1)
				(type default)
			)
			(layer "F.Fab")
		)
		(pad "1" smd circle
			(at -0.40005 0 270)
			(size 0 0)
			(layers "F.Cu" "F.Mask" "F.Paste")
			(net "P3V3_SSD11")
		)
		(pad "2" smd circle
			(at 0.40005 0 270)
			(size 0 0)
			(layers "F.Cu" "F.Mask" "F.Paste")
			(net "DUALPORT_N_SSD11")
		)
	)
	(footprint ""
		(layer "F.Cu")
		(at 32.417004 -308.852062 -135)
		(property "Reference" "R1259"
			(at 0 0 225)
			(layer "F.SilkS")
			(hide yes)
			(effects
				(font
					(size 1.27 1.27)
				)
			)
		)
		(property "Value" ""
			(at 0 0 225)
			(layer "F.Fab")
			(effects
				(font
					(size 1.27 1.27)
				)
			)
		)
		(duplicate_pad_numbers_are_jumpers no)
		(fp_line
			(start 0.787389 0.406267)
			(end -0.787389 0.406267)
			(stroke
				(width 0.1524)
				(type default)
			)
			(layer "F.SilkS")
		)
		(fp_line
			(start 0.787389 -0.406267)
			(end 0.787389 0.406267)
			(stroke
				(width 0.1524)
				(type default)
			)
			(layer "F.SilkS")
		)
		(fp_line
			(start -0.787389 0.406267)
			(end -0.787389 -0.406267)
			(stroke
				(width 0.1524)
				(type default)
			)
			(layer "F.SilkS")
		)
		(fp_line
			(start -0.787389 -0.406267)
			(end 0.787389 -0.406267)
			(stroke
				(width 0.1524)
				(type default)
			)
			(layer "F.SilkS")
		)
		(fp_line
			(start 0.679446 0.30479)
			(end 0.120515 0.30479)
			(stroke
				(width 0.1)
				(type default)
			)
			(layer "F.Fab")
		)
		(fp_line
			(start 0.120515 0.30479)
			(end 0.120335 0.279466)
			(stroke
				(width 0.1)
				(type default)
			)
			(layer "F.Fab")
		)
		(fp_line
			(start 0.120335 0.279466)
			(end -0.120695 0.279466)
			(stroke
				(width 0.1)
				(type default)
			)
			(layer "F.Fab")
		)
		(fp_line
			(start 0.679446 -0.30479)
			(end 0.679446 0.30479)
			(stroke
				(width 0.1)
				(type default)
			)
			(layer "F.Fab")
		)
		(fp_line
			(start -0.120515 0.30479)
			(end -0.679446 0.30479)
			(stroke
				(width 0.1)
				(type default)
			)
			(layer "F.Fab")
		)
		(fp_line
			(start -0.120695 0.279466)
			(end -0.120515 0.30479)
			(stroke
				(width 0.1)
				(type default)
			)
			(layer "F.Fab")
		)
		(fp_line
			(start 0.120695 -0.279466)
			(end 0.120515 -0.30479)
			(stroke
				(width 0.1)
				(type default)
			)
			(layer "F.Fab")
		)
		(fp_line
			(start 0.120515 -0.30479)
			(end 0.679446 -0.30479)
			(stroke
				(width 0.1)
				(type default)
			)
			(layer "F.Fab")
		)
		(fp_line
			(start -0.679446 0.30479)
			(end -0.679446 -0.305149)
			(stroke
				(width 0.1)
				(type default)
			)
			(layer "F.Fab")
		)
		(fp_line
			(start -0.120695 -0.279466)
			(end 0.120695 -0.279466)
			(stroke
				(width 0.1)
				(type default)
			)
			(layer "F.Fab")
		)
		(fp_line
			(start -0.120695 -0.304969)
			(end -0.120695 -0.279466)
			(stroke
				(width 0.1)
				(type default)
			)
			(layer "F.Fab")
		)
		(fp_line
			(start -0.679446 -0.305149)
			(end -0.120695 -0.304969)
			(stroke
				(width 0.1)
				(type default)
			)
			(layer "F.Fab")
		)
		(pad "1" smd circle
			(at -0.40005 0 225)
			(size 0 0)
			(layers "F.Cu" "F.Mask" "F.Paste")
			(net "PU_PEX0_ATPG_MODE_L")
		)
		(pad "2" smd circle
			(at 0.40005 0 225)
			(size 0 0)
			(layers "F.Cu" "F.Mask" "F.Paste")
			(net "P1V8_PEX")
		)
	)
	(footprint ""
		(layer "F.Cu")
		(at 32.657288 -343.952322 90)
		(property "Reference" "C2163"
			(at 0 0 90)
			(layer "F.SilkS")
			(hide yes)
			(effects
				(font
					(size 1.27 1.27)
				)
			)
		)
		(property "Value" ""
			(at 0 0 90)
			(layer "F.Fab")
			(effects
				(font
					(size 1.27 1.27)
				)
			)
		)
		(duplicate_pad_numbers_are_jumpers no)
		(fp_line
			(start 0.299974 -0.150114)
			(end 0.299974 0.150114)
			(stroke
				(width 0.1)
				(type default)
			)
			(layer "F.Fab")
		)
		(fp_line
			(start -0.299974 -0.150114)
			(end 0.299974 -0.150114)
			(stroke
				(width 0.1)
				(type default)
			)
			(layer "F.Fab")
		)
		(fp_line
			(start 0.299974 0.150114)
			(end -0.299974 0.150114)
			(stroke
				(width 0.1)
				(type default)
			)
			(layer "F.Fab")
		)
		(fp_line
			(start -0.299974 0.150114)
			(end -0.299974 -0.150114)
			(stroke
				(width 0.1)
				(type default)
			)
			(layer "F.Fab")
		)
		(pad "1" smd rect
			(at -0.2667 0 90)
			(size 0.3048 0.381)
			(layers "F.Cu" "F.Mask" "F.Paste")
			(net "P5E_PEX0_STN4_TX_DN<74>")
		)
		(pad "2" smd rect
			(at 0.2667 0 90)
			(size 0.3048 0.381)
			(layers "F.Cu" "F.Mask" "F.Paste")
			(net "P5E_PEX0_STN4_TX_C_DN<74>")
		)
	)
	(footprint ""
		(layer "F.Cu")
		(at 434.141372 -356.244906 90)
		(property "Reference" "C800"
			(at 0 0 90)
			(layer "F.SilkS")
			(hide yes)
			(effects
				(font
					(size 1.27 1.27)
				)
			)
		)
		(property "Value" ""
			(at 0 0 90)
			(layer "F.Fab")
			(effects
				(font
					(size 1.27 1.27)
				)
			)
		)
		(duplicate_pad_numbers_are_jumpers no)
		(fp_line
			(start 0.299974 -0.150114)
			(end 0.299974 0.150114)
			(stroke
				(width 0.1)
				(type default)
			)
			(layer "F.Fab")
		)
		(fp_line
			(start -0.299974 -0.150114)
			(end 0.299974 -0.150114)
			(stroke
				(width 0.1)
				(type default)
			)
			(layer "F.Fab")
		)
		(fp_line
			(start 0.299974 0.150114)
			(end -0.299974 0.150114)
			(stroke
				(width 0.1)
				(type default)
			)
			(layer "F.Fab")
		)
		(fp_line
			(start -0.299974 0.150114)
			(end -0.299974 -0.150114)
			(stroke
				(width 0.1)
				(type default)
			)
			(layer "F.Fab")
		)
		(pad "1" smd rect
			(at -0.2667 0 90)
			(size 0.3048 0.381)
			(layers "F.Cu" "F.Mask" "F.Paste")
			(net "P5E_PEX3_STN7_TX_DP<124>")
		)
		(pad "2" smd rect
			(at 0.2667 0 90)
			(size 0.3048 0.381)
			(layers "F.Cu" "F.Mask" "F.Paste")
			(net "P5E_PEX3_STN7_TX_C_DP<124>")
		)
	)
)
